# BASEBOARD_FAB2 (Tioga Pass) — schematic netlist excerpt (pin names and nets, part order shuffled) for the footprints in the layout excerpt that follows; sources: Cadence DE-HDL packaged netlist, KiCad conversion of Wiwynn_Tioga_Pass_MB.brd

R7P20  RES  150.0 1% CHIP  pkg 0402  page 97 : A = PVCCIO_CPU0 ; B = H_CPU1_FAST_WAKE_N
R3M10  RES  1.00K 1% CHIP  pkg 0402  page 112 : A = XDP_PCH_CPU_TCK0 ; B = GND

(kicad_pcb
	(version 20260206)
	(generator "pcbnew")
	(generator_version "10.0")
	(general
		(thickness 1.6)
		(legacy_teardrops no)
	)
	(paper "A4")
	(title_block
		(title "Wiwynn_Tioga_Pass_MB.brd")
		(comment 1 "Tioga Pass / footprints 3390-3391 of 4770")
	)
	(layers
		(0 "F.Cu" signal "TOP")
		(4 "In1.Cu" signal "L2GND")
		(6 "In2.Cu" signal "L3")
		(8 "In3.Cu" signal "L4GND")
		(10 "In4.Cu" signal "L5")
		(12 "In5.Cu" signal "L6GND")
		(14 "In6.Cu" signal "L7VCC")
		(16 "In7.Cu" signal "L8VCC")
		(18 "In8.Cu" signal "L9GND")
		(20 "In9.Cu" signal "L10")
		(22 "In10.Cu" signal "L11GND")
		(24 "In11.Cu" signal "L12")
		(26 "In12.Cu" signal "L13GND")
		(2 "B.Cu" signal "BOTTOM")
		(9 "F.Adhes" user "F.Adhesive")
		(11 "B.Adhes" user "B.Adhesive")
		(13 "F.Paste" user "Package Geometry/Pastemask Top")
		(15 "B.Paste" user "Package Geometry/Pastemask Bottom")
		(5 "F.SilkS" user "Ref Des/Silkscreen Top")
		(7 "B.SilkS" user "Ref Des/Silkscreen Bottom")
		(1 "F.Mask" user "Board Geometry/Soldermask Top")
		(3 "B.Mask" user "Board Geometry/Soldermask Bottom")
		(17 "Dwgs.User" user "User.Drawings")
		(19 "Cmts.User" user "User.Comments")
		(21 "Eco1.User" user "User.Eco1")
		(23 "Eco2.User" user "User.Eco2")
		(25 "Edge.Cuts" user "Board Geometry/Outline")
		(27 "Margin" user)
		(31 "F.CrtYd" user "Package Geometry/Place Bound Top")
		(29 "B.CrtYd" user "Package Geometry/Place Bound Bottom")
		(35 "F.Fab" user "Ref Des/Assembly Top")
		(33 "B.Fab" user "Ref Des/Assembly Bottom")
	)
	(footprint ""
		(layer "B.Cu")
		(at 386.80898 -126.9238 180)
		(property "Reference" "R3M10"
			(at 0 0 0)
			(layer "B.SilkS")
			(hide yes)
			(effects
				(font
					(size 1.27 1.27)
				)
				(justify mirror)
			)
		)
		(property "Value" ""
			(at 0 0 0)
			(layer "B.Fab")
			(effects
				(font
					(size 1.27 1.27)
				)
				(justify mirror)
			)
		)
		(duplicate_pad_numbers_are_jumpers no)
		(fp_poly
			(pts
				(xy 0.2794 -0.1016) (xy -0.2794 -0.1016) (xy -0.2794 0.9906) (xy 0.2794 0.9906)
			)
			(stroke
				(width 0)
				(type default)
			)
			(fill no)
			(layer "B.CrtYd")
		)
		(fp_line
			(start 0.2794 0.9906)
			(end -0.2794 0.9906)
			(stroke
				(width 0.1)
				(type default)
			)
			(layer "B.Fab")
		)
		(fp_line
			(start 0.2794 -0.1016)
			(end 0.2794 0.9906)
			(stroke
				(width 0.1)
				(type default)
			)
			(layer "B.Fab")
		)
		(fp_line
			(start -0.2794 0.9906)
			(end -0.2794 -0.1016)
			(stroke
				(width 0.1)
				(type default)
			)
			(layer "B.Fab")
		)
		(fp_line
			(start -0.2794 -0.1016)
			(end 0.2794 -0.1016)
			(stroke
				(width 0.1)
				(type default)
			)
			(layer "B.Fab")
		)
		(pad "1" smd rect
			(at 0 0)
			(size 0.508 0.508)
			(layers "B.Cu" "B.Mask" "B.Paste")
			(net "XDP_PCH_CPU_TCK0")
		)
		(pad "2" smd rect
			(at 0 0.889)
			(size 0.508 0.508)
			(layers "B.Cu" "B.Mask" "B.Paste")
			(net "GND")
		)
		(zone
			(layer "B.Cu")
			(hatch none 0.5)
			(connect_pads
				(clearance 0)
			)
			(min_thickness 0.25)
			(keepout
				(tracks not_allowed)
				(vias allowed)
				(pads allowed)
				(copperpour not_allowed)
				(footprints allowed)
			)
			(placement
				(enabled no)
				(sheetname "")
			)
			(fill
				(thermal_gap 0.5)
				(thermal_bridge_width 0.5)
				(island_removal_mode 0)
			)
			(polygon
				(pts
					(xy 386.55498 -127.5588) (xy 387.06298 -127.5588) (xy 387.06298 -127.1778) (xy 386.55498 -127.1778)
				)
			)
		)
		(zone
			(layer "B.Cu")
			(hatch none 0.5)
			(connect_pads
				(clearance 0)
			)
			(min_thickness 0.25)
			(keepout
				(tracks allowed)
				(vias not_allowed)
				(pads allowed)
				(copperpour not_allowed)
				(footprints allowed)
			)
			(placement
				(enabled no)
				(sheetname "")
			)
			(fill
				(thermal_gap 0.5)
				(thermal_bridge_width 0.5)
				(island_removal_mode 0)
			)
			(polygon
				(pts
					(xy 386.55498 -127.1778) (xy 387.06298 -127.1778) (xy 387.06298 -127.5588) (xy 386.55498 -127.5588)
				)
			)
		)
	)
	(footprint ""
		(layer "B.Cu")
		(at 162.179 -69.596)
		(property "Reference" "R7P20"
			(at 0 0 0)
			(layer "B.SilkS")
			(hide yes)
			(effects
				(font
					(size 1.27 1.27)
				)
				(justify mirror)
			)
		)
		(property "Value" ""
			(at 0 0 0)
			(layer "B.Fab")
			(effects
				(font
					(size 1.27 1.27)
				)
				(justify mirror)
			)
		)
		(duplicate_pad_numbers_are_jumpers no)
		(fp_poly
			(pts
				(xy 0.2794 -0.1016) (xy -0.2794 -0.1016) (xy -0.2794 0.9906) (xy 0.2794 0.9906)
			)
			(stroke
				(width 0)
				(type default)
			)
			(fill no)
			(layer "B.CrtYd")
		)
		(fp_line
			(start -0.2794 -0.1016)
			(end 0.2794 -0.1016)
			(stroke
				(width 0.1)
				(type default)
			)
			(layer "B.Fab")
		)
		(fp_line
			(start -0.2794 0.9906)
			(end -0.2794 -0.1016)
			(stroke
				(width 0.1)
				(type default)
			)
			(layer "B.Fab")
		)
		(fp_line
			(start 0.2794 -0.1016)
			(end 0.2794 0.9906)
			(stroke
				(width 0.1)
				(type default)
			)
			(layer "B.Fab")
		)
		(fp_line
			(start 0.2794 0.9906)
			(end -0.2794 0.9906)
			(stroke
				(width 0.1)
				(type default)
			)
			(layer "B.Fab")
		)
		(pad "1" smd rect
			(at 0 0 180)
			(size 0.508 0.508)
			(layers "B.Cu" "B.Mask" "B.Paste")
			(net "PVCCIO_CPU0")
		)
		(pad "2" smd rect
			(at 0 0.889 180)
			(size 0.508 0.508)
			(layers "B.Cu" "B.Mask" "B.Paste")
			(net "H_CPU1_FAST_WAKE_N")
		)
		(zone
			(layer "B.Cu")
			(hatch none 0.5)
			(connect_pads
				(clearance 0)
			)
			(min_thickness 0.25)
			(keepout
				(tracks allowed)
				(vias not_allowed)
				(pads allowed)
				(copperpour not_allowed)
				(footprints allowed)
			)
			(placement
				(enabled no)
				(sheetname "")
			)
			(fill
				(thermal_gap 0.5)
				(thermal_bridge_width 0.5)
				(island_removal_mode 0)
			)
			(polygon
				(pts
					(xy 162.433 -69.342) (xy 161.925 -69.342) (xy 161.925 -68.961) (xy 162.433 -68.961)
				)
			)
		)
		(zone
			(layer "B.Cu")
			(hatch none 0.5)
			(connect_pads
				(clearance 0)
			)
			(min_thickness 0.25)
			(keepout
				(tracks not_allowed)
				(vias allowed)
				(pads allowed)
				(copperpour not_allowed)
				(footprints allowed)
			)
			(placement
				(enabled no)
				(sheetname "")
			)
			(fill
				(thermal_gap 0.5)
				(thermal_bridge_width 0.5)
				(island_removal_mode 0)
			)
			(polygon
				(pts
					(xy 162.433 -68.961) (xy 161.925 -68.961) (xy 161.925 -69.342) (xy 162.433 -69.342)
				)
			)
		)
	)
)
